# SCM (Grand Teton) — schematic netlist excerpt (pin names and nets, part order shuffled) for the footprints in the layout excerpt that follows; sources: Cadence DE-HDL packaged netlist, KiCad conversion of 12092022_DA0F0TMDCD0_F0T_Management_Board_D_brd_V3_OCP.brd

R676  Q_RES  0 5% CHIP  pkg 0402LF  page 47 : A = LED_POSTCODE_5 ; B = LED_POSTCODE_5_R1
C39  Q_CAP  0.1UF 25V 10% X7R  pkg 0402  page 15 : A = P3V3_P1V8_SD2VDD ; B = GND

(kicad_pcb
	(version 20260206)
	(generator "pcbnew")
	(generator_version "10.0")
	(general
		(thickness 1.6)
		(legacy_teardrops no)
	)
	(paper "A4")
	(title_block
		(title "12092022_DA0F0TMDCD0_F0T_Management_Board_D_brd_V3_OCP.brd")
		(comment 1 "Grand Teton / footprints 1059-1060 of 1440")
	)
	(layers
		(0 "F.Cu" signal "TOP")
		(4 "In1.Cu" signal "GND")
		(6 "In2.Cu" signal "IN1")
		(8 "In3.Cu" signal "GND1")
		(10 "In4.Cu" signal "IN2")
		(12 "In5.Cu" signal "VCC")
		(14 "In6.Cu" signal "VCC1")
		(16 "In7.Cu" signal "IN3")
		(18 "In8.Cu" signal "GND2")
		(20 "In9.Cu" signal "IN4")
		(22 "In10.Cu" signal "GND3")
		(2 "B.Cu" signal "BOTTOM")
		(9 "F.Adhes" user "F.Adhesive")
		(11 "B.Adhes" user "B.Adhesive")
		(13 "F.Paste" user "Package Geometry/Pastemask Top")
		(15 "B.Paste" user "Package Geometry/Pastemask Bottom")
		(5 "F.SilkS" user "Ref Des/Silkscreen Top")
		(7 "B.SilkS" user "Ref Des/Silkscreen Bottom")
		(1 "F.Mask" user "Board Geometry/Soldermask Top")
		(3 "B.Mask" user "Board Geometry/Soldermask Bottom")
		(17 "Dwgs.User" user "User.Drawings")
		(19 "Cmts.User" user "User.Comments")
		(21 "Eco1.User" user "User.Eco1")
		(23 "Eco2.User" user "User.Eco2")
		(25 "Edge.Cuts" user "Board Geometry/Outline")
		(27 "Margin" user)
		(31 "F.CrtYd" user "Package Geometry/Place Bound Top")
		(29 "B.CrtYd" user "Package Geometry/Place Bound Bottom")
		(35 "F.Fab" user "Ref Des/Assembly Top")
		(33 "B.Fab" user "Ref Des/Assembly Bottom")
	)
	(footprint ""
		(layer "B.Cu")
		(at 51.255422 -45.204126 180)
		(property "Reference" "C39"
			(at 0 0 0)
			(layer "B.SilkS")
			(hide yes)
			(effects
				(font
					(size 1.27 1.27)
				)
				(justify mirror)
			)
		)
		(property "Value" ""
			(at 0 0 0)
			(layer "B.Fab")
			(effects
				(font
					(size 1.27 1.27)
				)
				(justify mirror)
			)
		)
		(duplicate_pad_numbers_are_jumpers no)
		(fp_line
			(start 0.7874 0.4064)
			(end 0.7874 -0.4064)
			(stroke
				(width 0.1524)
				(type default)
			)
			(layer "B.SilkS")
		)
		(fp_line
			(start 0.7874 -0.4064)
			(end -0.7874 -0.4064)
			(stroke
				(width 0.1524)
				(type default)
			)
			(layer "B.SilkS")
		)
		(fp_line
			(start -0.7874 0.4064)
			(end 0.7874 0.4064)
			(stroke
				(width 0.1524)
				(type default)
			)
			(layer "B.SilkS")
		)
		(fp_line
			(start -0.7874 -0.4064)
			(end -0.7874 0.4064)
			(stroke
				(width 0.1524)
				(type default)
			)
			(layer "B.SilkS")
		)
		(fp_line
			(start 0.67945 0.3048)
			(end 0.67945 -0.305054)
			(stroke
				(width 0.1)
				(type default)
			)
			(layer "B.Fab")
		)
		(fp_line
			(start 0.67945 -0.305054)
			(end 0.12065 -0.305054)
			(stroke
				(width 0.1)
				(type default)
			)
			(layer "B.Fab")
		)
		(fp_line
			(start 0.12065 0.3048)
			(end 0.67945 0.3048)
			(stroke
				(width 0.1)
				(type default)
			)
			(layer "B.Fab")
		)
		(fp_line
			(start 0.12065 0.2794)
			(end 0.12065 0.3048)
			(stroke
				(width 0.1)
				(type default)
			)
			(layer "B.Fab")
		)
		(fp_line
			(start 0.12065 -0.2794)
			(end -0.12065 -0.2794)
			(stroke
				(width 0.1)
				(type default)
			)
			(layer "B.Fab")
		)
		(fp_line
			(start 0.12065 -0.305054)
			(end 0.12065 -0.2794)
			(stroke
				(width 0.1)
				(type default)
			)
			(layer "B.Fab")
		)
		(fp_line
			(start -0.120396 0.3048)
			(end -0.120396 0.2794)
			(stroke
				(width 0.1)
				(type default)
			)
			(layer "B.Fab")
		)
		(fp_line
			(start -0.120396 0.2794)
			(end 0.12065 0.2794)
			(stroke
				(width 0.1)
				(type default)
			)
			(layer "B.Fab")
		)
		(fp_line
			(start -0.12065 -0.2794)
			(end -0.12065 -0.3048)
			(stroke
				(width 0.1)
				(type default)
			)
			(layer "B.Fab")
		)
		(fp_line
			(start -0.12065 -0.3048)
			(end -0.67945 -0.3048)
			(stroke
				(width 0.1)
				(type default)
			)
			(layer "B.Fab")
		)
		(fp_line
			(start -0.67945 0.3048)
			(end -0.120396 0.3048)
			(stroke
				(width 0.1)
				(type default)
			)
			(layer "B.Fab")
		)
		(fp_line
			(start -0.67945 -0.3048)
			(end -0.67945 0.3048)
			(stroke
				(width 0.1)
				(type default)
			)
			(layer "B.Fab")
		)
		(pad "1" smd circle
			(at 0.40005 0)
			(size 0 0)
			(layers "B.Cu" "B.Mask" "B.Paste")
			(net "P3V3_P1V8_SD2VDD")
		)
		(pad "2" smd circle
			(at -0.40005 0)
			(size 0 0)
			(layers "B.Cu" "B.Mask" "B.Paste")
			(net "GND")
		)
	)
	(footprint ""
		(layer "B.Cu")
		(at 77.47 -31.115 90)
		(property "Reference" "R676"
			(at 0 0 90)
			(layer "B.SilkS")
			(hide yes)
			(effects
				(font
					(size 1.27 1.27)
				)
				(justify mirror)
			)
		)
		(property "Value" ""
			(at 0 0 90)
			(layer "B.Fab")
			(effects
				(font
					(size 1.27 1.27)
				)
				(justify mirror)
			)
		)
		(duplicate_pad_numbers_are_jumpers no)
		(fp_line
			(start 0.7874 -0.4064)
			(end -0.7874 -0.4064)
			(stroke
				(width 0.1524)
				(type default)
			)
			(layer "B.SilkS")
		)
		(fp_line
			(start -0.7874 -0.4064)
			(end -0.7874 0.4064)
			(stroke
				(width 0.1524)
				(type default)
			)
			(layer "B.SilkS")
		)
		(fp_line
			(start 0.7874 0.4064)
			(end 0.7874 -0.4064)
			(stroke
				(width 0.1524)
				(type default)
			)
			(layer "B.SilkS")
		)
		(fp_line
			(start -0.7874 0.4064)
			(end 0.7874 0.4064)
			(stroke
				(width 0.1524)
				(type default)
			)
			(layer "B.SilkS")
		)
		(fp_line
			(start 0.67945 -0.305054)
			(end 0.12065 -0.305054)
			(stroke
				(width 0.1)
				(type default)
			)
			(layer "B.Fab")
		)
		(fp_line
			(start 0.12065 -0.305054)
			(end 0.12065 -0.2794)
			(stroke
				(width 0.1)
				(type default)
			)
			(layer "B.Fab")
		)
		(fp_line
			(start -0.12065 -0.3048)
			(end -0.67945 -0.3048)
			(stroke
				(width 0.1)
				(type default)
			)
			(layer "B.Fab")
		)
		(fp_line
			(start -0.67945 -0.3048)
			(end -0.67945 0.3048)
			(stroke
				(width 0.1)
				(type default)
			)
			(layer "B.Fab")
		)
		(fp_line
			(start 0.12065 -0.2794)
			(end -0.12065 -0.2794)
			(stroke
				(width 0.1)
				(type default)
			)
			(layer "B.Fab")
		)
		(fp_line
			(start -0.12065 -0.2794)
			(end -0.12065 -0.3048)
			(stroke
				(width 0.1)
				(type default)
			)
			(layer "B.Fab")
		)
		(fp_line
			(start 0.12065 0.2794)
			(end 0.12065 0.3048)
			(stroke
				(width 0.1)
				(type default)
			)
			(layer "B.Fab")
		)
		(fp_line
			(start -0.120396 0.2794)
			(end 0.12065 0.2794)
			(stroke
				(width 0.1)
				(type default)
			)
			(layer "B.Fab")
		)
		(fp_line
			(start 0.67945 0.3048)
			(end 0.67945 -0.305054)
			(stroke
				(width 0.1)
				(type default)
			)
			(layer "B.Fab")
		)
		(fp_line
			(start 0.12065 0.3048)
			(end 0.67945 0.3048)
			(stroke
				(width 0.1)
				(type default)
			)
			(layer "B.Fab")
		)
		(fp_line
			(start -0.120396 0.3048)
			(end -0.120396 0.2794)
			(stroke
				(width 0.1)
				(type default)
			)
			(layer "B.Fab")
		)
		(fp_line
			(start -0.67945 0.3048)
			(end -0.120396 0.3048)
			(stroke
				(width 0.1)
				(type default)
			)
			(layer "B.Fab")
		)
		(pad "1" smd circle
			(at 0.40005 0 270)
			(size 0 0)
			(layers "B.Cu" "B.Mask" "B.Paste")
			(net "LED_POSTCODE_5")
		)
		(pad "2" smd circle
			(at -0.40005 0 270)
			(size 0 0)
			(layers "B.Cu" "B.Mask" "B.Paste")
			(net "LED_POSTCODE_5_R1")
		)
	)
)
